FILE_TYPE = CONNECTIVITY;
{Allegro Design Entry HDL 17.4-2019 S026 (4007227) 1/17/2022}
"PAGE_NUMBER" = 356;
0"NC";
END.
